(kicad_pcb
	(version 20260206)
	(generator "pcbnew")
	(generator_version "10.0")
	(general
		(thickness 1.6)
		(legacy_teardrops no)
	)
	(paper "A4")
	(title_block
		(title "03242023_DA0F0TMBIJ0_F0T_Motherboard_J_brd_V01_OCP.brd")
		(comment 1 "Grand Teton / footprints 8-14 of 6105")
	)
	(layers
		(0 "F.Cu" signal "TOP")
		(4 "In1.Cu" signal "GND")
		(6 "In2.Cu" signal "IN1")
		(8 "In3.Cu" signal "GND1")
		(10 "In4.Cu" signal "IN2")
		(12 "In5.Cu" signal "GND2")
		(14 "In6.Cu" signal "IN3")
		(16 "In7.Cu" signal "GND3")
		(18 "In8.Cu" signal "VCC")
		(20 "In9.Cu" signal "VCC1")
		(22 "In10.Cu" signal "GND4")
		(24 "In11.Cu" signal "IN4")
		(26 "In12.Cu" signal "GND5")
		(28 "In13.Cu" signal "IN5")
		(30 "In14.Cu" signal "GND6")
		(32 "In15.Cu" signal "IN6")
		(34 "In16.Cu" signal "GND7")
		(2 "B.Cu" signal "BOTTOM")
		(9 "F.Adhes" user "F.Adhesive")
		(11 "B.Adhes" user "B.Adhesive")
		(13 "F.Paste" user "Package Geometry/Pastemask Top")
		(15 "B.Paste" user "Package Geometry/Pastemask Bottom")
		(5 "F.SilkS" user "Ref Des/Silkscreen Top")
		(7 "B.SilkS" user "Ref Des/Silkscreen Bottom")
		(1 "F.Mask" user "Board Geometry/Soldermask Top")
		(3 "B.Mask" user "Board Geometry/Soldermask Bottom")
		(17 "Dwgs.User" user "User.Drawings")
		(19 "Cmts.User" user "User.Comments")
		(21 "Eco1.User" user "User.Eco1")
		(23 "Eco2.User" user "User.Eco2")
		(25 "Edge.Cuts" user "Board Geometry/Outline")
		(27 "Margin" user)
		(31 "F.CrtYd" user "Package Geometry/Place Bound Top")
		(29 "B.CrtYd" user "Package Geometry/Place Bound Bottom")
		(35 "F.Fab" user "Ref Des/Assembly Top")
		(33 "B.Fab" user "Ref Des/Assembly Bottom")
	)
	(footprint ""
		(layer "F.Cu")
		(at 180.528468 -50.974498 180)
		(property "Reference" "C1102"
			(at 0 0 180)
			(layer "F.SilkS")
			(hide yes)
			(effects
				(font
					(size 1.27 1.27)
				)
			)
		)
		(property "Value" ""
			(at 0 0 180)
			(layer "F.Fab")
			(effects
				(font
					(size 1.27 1.27)
				)
			)
		)
		(duplicate_pad_numbers_are_jumpers no)
		(fp_line
			(start 0.299974 0.150114)
			(end -0.299974 0.150114)
			(stroke
				(width 0.1)
				(type default)
			)
			(layer "F.Fab")
		)
		(fp_line
			(start 0.299974 -0.150114)
			(end 0.299974 0.150114)
			(stroke
				(width 0.1)
				(type default)
			)
			(layer "F.Fab")
		)
		(fp_line
			(start -0.299974 0.150114)
			(end -0.299974 -0.150114)
			(stroke
				(width 0.1)
				(type default)
			)
			(layer "F.Fab")
		)
		(fp_line
			(start -0.299974 -0.150114)
			(end 0.299974 -0.150114)
			(stroke
				(width 0.1)
				(type default)
			)
			(layer "F.Fab")
		)
		(pad "1" smd rect
			(at -0.2667 0 180)
			(size 0.3048 0.381)
			(layers "F.Cu" "F.Mask" "F.Paste")
			(net "P3E_PCH_M2_TX_DP<1>")
		)
		(pad "2" smd rect
			(at 0.2667 0 180)
			(size 0.3048 0.381)
			(layers "F.Cu" "F.Mask" "F.Paste")
			(net "P3E_PCH_M2_TX_C_DP<1>")
		)
		(zone
			(layer "In1.Cu")
			(hatch none 0.5)
			(connect_pads
				(clearance 0)
			)
			(min_thickness 0.25)
			(keepout
				(tracks not_allowed)
				(vias allowed)
				(pads allowed)
				(copperpour not_allowed)
				(footprints allowed)
			)
			(placement
				(enabled no)
				(sheetname "")
			)
			(fill
				(thermal_gap 0.5)
				(thermal_bridge_width 0.5)
				(island_removal_mode 0)
			)
			(polygon
				(pts
					(arc
						(start 180.388768 -51.215798)
						(mid 180.44265 -51.19348)
						(end 180.464968 -51.139598)
					)
					(arc
						(start 180.464968 -50.809398)
						(mid 180.44265 -50.755516)
						(end 180.388768 -50.733198)
					)
					(arc
						(start 180.134768 -50.733198)
						(mid 180.080886 -50.755516)
						(end 180.058568 -50.809398)
					)
					(arc
						(start 180.058568 -51.139598)
						(mid 180.080886 -51.19348)
						(end 180.134768 -51.215798)
					)
				)
			)
		)
		(zone
			(layer "In1.Cu")
			(hatch none 0.5)
			(connect_pads
				(clearance 0)
			)
			(min_thickness 0.25)
			(keepout
				(tracks not_allowed)
				(vias allowed)
				(pads allowed)
				(copperpour not_allowed)
				(footprints allowed)
			)
			(placement
				(enabled no)
				(sheetname "")
			)
			(fill
				(thermal_gap 0.5)
				(thermal_bridge_width 0.5)
				(island_removal_mode 0)
			)
			(polygon
				(pts
					(arc
						(start 180.922168 -51.215798)
						(mid 180.97605 -51.19348)
						(end 180.998368 -51.139598)
					)
					(arc
						(start 180.998368 -50.809398)
						(mid 180.97605 -50.755516)
						(end 180.922168 -50.733198)
					)
					(arc
						(start 180.668168 -50.733198)
						(mid 180.614286 -50.755516)
						(end 180.591968 -50.809398)
					)
					(arc
						(start 180.591968 -51.139598)
						(mid 180.614286 -51.19348)
						(end 180.668168 -51.215798)
					)
				)
			)
		)
	)
	(footprint ""
		(layer "F.Cu")
		(at 438.28208 -16.220948 -90)
		(property "Reference" "R416"
			(at 0 0 270)
			(layer "F.SilkS")
			(hide yes)
			(effects
				(font
					(size 1.27 1.27)
				)
			)
		)
		(property "Value" ""
			(at 0 0 270)
			(layer "F.Fab")
			(effects
				(font
					(size 1.27 1.27)
				)
			)
		)
		(duplicate_pad_numbers_are_jumpers no)
		(fp_line
			(start -0.7874 0.4064)
			(end -0.7874 -0.4064)
			(stroke
				(width 0.1524)
				(type default)
			)
			(layer "F.SilkS")
		)
		(fp_line
			(start 0.7874 0.4064)
			(end -0.7874 0.4064)
			(stroke
				(width 0.1524)
				(type default)
			)
			(layer "F.SilkS")
		)
		(fp_line
			(start -0.7874 -0.4064)
			(end 0.7874 -0.4064)
			(stroke
				(width 0.1524)
				(type default)
			)
			(layer "F.SilkS")
		)
		(fp_line
			(start 0.7874 -0.4064)
			(end 0.7874 0.4064)
			(stroke
				(width 0.1524)
				(type default)
			)
			(layer "F.SilkS")
		)
		(fp_line
			(start -0.67945 0.3048)
			(end -0.67945 -0.305054)
			(stroke
				(width 0.1)
				(type default)
			)
			(layer "F.Fab")
		)
		(fp_line
			(start -0.12065 0.3048)
			(end -0.67945 0.3048)
			(stroke
				(width 0.1)
				(type default)
			)
			(layer "F.Fab")
		)
		(fp_line
			(start 0.120396 0.3048)
			(end 0.120396 0.2794)
			(stroke
				(width 0.1)
				(type default)
			)
			(layer "F.Fab")
		)
		(fp_line
			(start 0.67945 0.3048)
			(end 0.120396 0.3048)
			(stroke
				(width 0.1)
				(type default)
			)
			(layer "F.Fab")
		)
		(fp_line
			(start -0.12065 0.2794)
			(end -0.12065 0.3048)
			(stroke
				(width 0.1)
				(type default)
			)
			(layer "F.Fab")
		)
		(fp_line
			(start 0.120396 0.2794)
			(end -0.12065 0.2794)
			(stroke
				(width 0.1)
				(type default)
			)
			(layer "F.Fab")
		)
		(fp_line
			(start -0.12065 -0.2794)
			(end 0.12065 -0.2794)
			(stroke
				(width 0.1)
				(type default)
			)
			(layer "F.Fab")
		)
		(fp_line
			(start 0.12065 -0.2794)
			(end 0.12065 -0.3048)
			(stroke
				(width 0.1)
				(type default)
			)
			(layer "F.Fab")
		)
		(fp_line
			(start 0.12065 -0.3048)
			(end 0.67945 -0.3048)
			(stroke
				(width 0.1)
				(type default)
			)
			(layer "F.Fab")
		)
		(fp_line
			(start 0.67945 -0.3048)
			(end 0.67945 0.3048)
			(stroke
				(width 0.1)
				(type default)
			)
			(layer "F.Fab")
		)
		(fp_line
			(start -0.67945 -0.305054)
			(end -0.12065 -0.305054)
			(stroke
				(width 0.1)
				(type default)
			)
			(layer "F.Fab")
		)
		(fp_line
			(start -0.12065 -0.305054)
			(end -0.12065 -0.2794)
			(stroke
				(width 0.1)
				(type default)
			)
			(layer "F.Fab")
		)
		(pad "1" smd circle
			(at -0.40005 0 270)
			(size 0 0)
			(layers "F.Cu" "F.Mask" "F.Paste")
			(net "OCP_SFF_ISO_BIF0_EN")
		)
		(pad "2" smd circle
			(at 0.40005 0 270)
			(size 0 0)
			(layers "F.Cu" "F.Mask" "F.Paste")
			(net "OCP_SFF_BIF0_R_N")
		)
	)
	(footprint ""
		(layer "F.Cu")
		(at 145.940018 -251.76988)
		(property "Reference" "H26"
			(at 2.44602 -1.372108 0)
			(unlocked yes)
			(layer "F.SilkS")
			(effects
				(font
					(size 0.7874 0.5842)
					(thickness 0.1524)
				)
				(justify left)
			)
		)
		(property "Value" ""
			(at 0 0 0)
			(layer "F.Fab")
			(effects
				(font
					(size 1.27 1.27)
				)
			)
		)
		(duplicate_pad_numbers_are_jumpers no)
		(fp_circle
			(center 0 0)
			(end 2.5273 0)
			(stroke
				(width 0.1524)
				(type default)
			)
			(fill no)
			(layer "F.SilkS")
		)
		(fp_circle
			(center 0 0)
			(end 2.5273 0)
			(stroke
				(width 0.1524)
				(type default)
			)
			(fill no)
			(layer "B.SilkS")
		)
		(fp_circle
			(center 0 0)
			(end 2.5273 0)
			(stroke
				(width 0.1)
				(type default)
			)
			(fill no)
			(layer "B.Fab")
		)
		(fp_circle
			(center 0 0)
			(end 2.5273 0)
			(stroke
				(width 0.1)
				(type default)
			)
			(fill no)
			(layer "F.Fab")
		)
		(pad "" np_thru_hole circle
			(at 0 0)
			(size 3.429 3.429)
			(drill 3.429)
			(layers "*.Cu" "*.Mask")
			(clearance 0.381)
			(thermal_gap 0.381)
		)
	)
	(footprint ""
		(layer "F.Cu")
		(at 440.60491 -179.92217)
		(property "Reference" "PL120"
			(at -0.05842 4.39293 0)
			(unlocked yes)
			(layer "F.SilkS")
			(effects
				(font
					(size 0.7874 0.5842)
					(thickness 0.1524)
				)
				(justify left)
			)
		)
		(property "Value" ""
			(at 0 0 0)
			(layer "F.Fab")
			(effects
				(font
					(size 1.27 1.27)
				)
			)
		)
		(duplicate_pad_numbers_are_jumpers no)
		(fp_line
			(start -3.6576 -3.350006)
			(end 3.64998 -3.350006)
			(stroke
				(width 0.1524)
				(type default)
			)
			(layer "F.SilkS")
		)
		(fp_line
			(start -3.64998 -1.8034)
			(end -3.64998 -3.350006)
			(stroke
				(width 0.1524)
				(type default)
			)
			(layer "F.SilkS")
		)
		(fp_line
			(start -3.64998 3.350006)
			(end -3.64998 1.8288)
			(stroke
				(width 0.1524)
				(type default)
			)
			(layer "F.SilkS")
		)
		(fp_line
			(start 3.64998 -3.350006)
			(end 3.64998 -1.8034)
			(stroke
				(width 0.1524)
				(type default)
			)
			(layer "F.SilkS")
		)
		(fp_line
			(start 3.64998 1.8034)
			(end 3.64998 3.350006)
			(stroke
				(width 0.1524)
				(type default)
			)
			(layer "F.SilkS")
		)
		(fp_line
			(start 3.64998 3.350006)
			(end -3.64998 3.350006)
			(stroke
				(width 0.1524)
				(type default)
			)
			(layer "F.SilkS")
		)
		(fp_line
			(start -3.64998 -3.350006)
			(end 3.64998 -3.350006)
			(stroke
				(width 0.1)
				(type default)
			)
			(layer "F.Fab")
		)
		(fp_line
			(start -3.64998 3.350006)
			(end -3.64998 -3.350006)
			(stroke
				(width 0.1)
				(type default)
			)
			(layer "F.Fab")
		)
		(fp_line
			(start 3.64998 -3.350006)
			(end 3.64998 3.350006)
			(stroke
				(width 0.1)
				(type default)
			)
			(layer "F.Fab")
		)
		(fp_line
			(start 3.64998 3.350006)
			(end -3.64998 3.350006)
			(stroke
				(width 0.1)
				(type default)
			)
			(layer "F.Fab")
		)
		(pad "1" smd rect
			(at -2.92481 0)
			(size 2.15392 3.302)
			(layers "F.Cu" "F.Mask" "F.Paste")
			(net "SW_PVNN_MAIN_CPU0_SW")
		)
		(pad "2" smd rect
			(at 2.92481 0)
			(size 2.15392 3.302)
			(layers "F.Cu" "F.Mask" "F.Paste")
			(net "PVNN_MAIN_CPU0")
		)
	)
	(footprint ""
		(layer "F.Cu")
		(at 381.148844 -337.214718 -90)
		(property "Reference" "PC255_P0_5"
			(at 0 0 270)
			(layer "F.SilkS")
			(hide yes)
			(effects
				(font
					(size 1.27 1.27)
				)
			)
		)
		(property "Value" ""
			(at 0 0 270)
			(layer "F.Fab")
			(effects
				(font
					(size 1.27 1.27)
				)
			)
		)
		(duplicate_pad_numbers_are_jumpers no)
		(fp_line
			(start -0.7874 0.4064)
			(end -0.7874 -0.4064)
			(stroke
				(width 0.1524)
				(type default)
			)
			(layer "F.SilkS")
		)
		(fp_line
			(start 0.7874 0.4064)
			(end -0.7874 0.4064)
			(stroke
				(width 0.1524)
				(type default)
			)
			(layer "F.SilkS")
		)
		(fp_line
			(start -0.7874 -0.4064)
			(end 0.7874 -0.4064)
			(stroke
				(width 0.1524)
				(type default)
			)
			(layer "F.SilkS")
		)
		(fp_line
			(start 0.7874 -0.4064)
			(end 0.7874 0.4064)
			(stroke
				(width 0.1524)
				(type default)
			)
			(layer "F.SilkS")
		)
		(fp_line
			(start -0.67945 0.3048)
			(end -0.67945 -0.305054)
			(stroke
				(width 0.1)
				(type default)
			)
			(layer "F.Fab")
		)
		(fp_line
			(start -0.12065 0.3048)
			(end -0.67945 0.3048)
			(stroke
				(width 0.1)
				(type default)
			)
			(layer "F.Fab")
		)
		(fp_line
			(start 0.120396 0.3048)
			(end 0.120396 0.2794)
			(stroke
				(width 0.1)
				(type default)
			)
			(layer "F.Fab")
		)
		(fp_line
			(start 0.67945 0.3048)
			(end 0.120396 0.3048)
			(stroke
				(width 0.1)
				(type default)
			)
			(layer "F.Fab")
		)
		(fp_line
			(start -0.12065 0.2794)
			(end -0.12065 0.3048)
			(stroke
				(width 0.1)
				(type default)
			)
			(layer "F.Fab")
		)
		(fp_line
			(start 0.120396 0.2794)
			(end -0.12065 0.2794)
			(stroke
				(width 0.1)
				(type default)
			)
			(layer "F.Fab")
		)
		(fp_line
			(start -0.12065 -0.2794)
			(end 0.12065 -0.2794)
			(stroke
				(width 0.1)
				(type default)
			)
			(layer "F.Fab")
		)
		(fp_line
			(start 0.12065 -0.2794)
			(end 0.12065 -0.3048)
			(stroke
				(width 0.1)
				(type default)
			)
			(layer "F.Fab")
		)
		(fp_line
			(start 0.12065 -0.3048)
			(end 0.67945 -0.3048)
			(stroke
				(width 0.1)
				(type default)
			)
			(layer "F.Fab")
		)
		(fp_line
			(start 0.67945 -0.3048)
			(end 0.67945 0.3048)
			(stroke
				(width 0.1)
				(type default)
			)
			(layer "F.Fab")
		)
		(fp_line
			(start -0.67945 -0.305054)
			(end -0.12065 -0.305054)
			(stroke
				(width 0.1)
				(type default)
			)
			(layer "F.Fab")
		)
		(fp_line
			(start -0.12065 -0.305054)
			(end -0.12065 -0.2794)
			(stroke
				(width 0.1)
				(type default)
			)
			(layer "F.Fab")
		)
		(pad "1" smd circle
			(at -0.40005 0 270)
			(size 0 0)
			(layers "F.Cu" "F.Mask" "F.Paste")
			(net "SW_P12V_PVCCIN_CPU0_FLT")
		)
		(pad "2" smd circle
			(at 0.40005 0 270)
			(size 0 0)
			(layers "F.Cu" "F.Mask" "F.Paste")
			(net "GND")
		)
	)
	(footprint ""
		(layer "F.Cu")
		(at 189.28588 -133.695948 90)
		(property "Reference" "R1742"
			(at 0 0 90)
			(layer "F.SilkS")
			(hide yes)
			(effects
				(font
					(size 1.27 1.27)
				)
			)
		)
		(property "Value" ""
			(at 0 0 90)
			(layer "F.Fab")
			(effects
				(font
					(size 1.27 1.27)
				)
			)
		)
		(duplicate_pad_numbers_are_jumpers no)
		(fp_line
			(start 0.7874 -0.4064)
			(end 0.7874 0.4064)
			(stroke
				(width 0.1524)
				(type default)
			)
			(layer "F.SilkS")
		)
		(fp_line
			(start -0.7874 -0.4064)
			(end 0.7874 -0.4064)
			(stroke
				(width 0.1524)
				(type default)
			)
			(layer "F.SilkS")
		)
		(fp_line
			(start 0.7874 0.4064)
			(end -0.7874 0.4064)
			(stroke
				(width 0.1524)
				(type default)
			)
			(layer "F.SilkS")
		)
		(fp_line
			(start -0.7874 0.4064)
			(end -0.7874 -0.4064)
			(stroke
				(width 0.1524)
				(type default)
			)
			(layer "F.SilkS")
		)
		(fp_line
			(start -0.12065 -0.305054)
			(end -0.12065 -0.2794)
			(stroke
				(width 0.1)
				(type default)
			)
			(layer "F.Fab")
		)
		(fp_line
			(start -0.67945 -0.305054)
			(end -0.12065 -0.305054)
			(stroke
				(width 0.1)
				(type default)
			)
			(layer "F.Fab")
		)
		(fp_line
			(start 0.67945 -0.3048)
			(end 0.67945 0.3048)
			(stroke
				(width 0.1)
				(type default)
			)
			(layer "F.Fab")
		)
		(fp_line
			(start 0.12065 -0.3048)
			(end 0.67945 -0.3048)
			(stroke
				(width 0.1)
				(type default)
			)
			(layer "F.Fab")
		)
		(fp_line
			(start 0.12065 -0.2794)
			(end 0.12065 -0.3048)
			(stroke
				(width 0.1)
				(type default)
			)
			(layer "F.Fab")
		)
		(fp_line
			(start -0.12065 -0.2794)
			(end 0.12065 -0.2794)
			(stroke
				(width 0.1)
				(type default)
			)
			(layer "F.Fab")
		)
		(fp_line
			(start 0.120396 0.2794)
			(end -0.12065 0.2794)
			(stroke
				(width 0.1)
				(type default)
			)
			(layer "F.Fab")
		)
		(fp_line
			(start -0.12065 0.2794)
			(end -0.12065 0.3048)
			(stroke
				(width 0.1)
				(type default)
			)
			(layer "F.Fab")
		)
		(fp_line
			(start 0.67945 0.3048)
			(end 0.120396 0.3048)
			(stroke
				(width 0.1)
				(type default)
			)
			(layer "F.Fab")
		)
		(fp_line
			(start 0.120396 0.3048)
			(end 0.120396 0.2794)
			(stroke
				(width 0.1)
				(type default)
			)
			(layer "F.Fab")
		)
		(fp_line
			(start -0.12065 0.3048)
			(end -0.67945 0.3048)
			(stroke
				(width 0.1)
				(type default)
			)
			(layer "F.Fab")
		)
		(fp_line
			(start -0.67945 0.3048)
			(end -0.67945 -0.305054)
			(stroke
				(width 0.1)
				(type default)
			)
			(layer "F.Fab")
		)
		(pad "1" smd circle
			(at -0.40005 0 90)
			(size 0 0)
			(layers "F.Cu" "F.Mask" "F.Paste")
			(net "FM_RST_PERST_BIT0")
		)
		(pad "2" smd circle
			(at 0.40005 0 90)
			(size 0 0)
			(layers "F.Cu" "F.Mask" "F.Paste")
			(net "GND")
		)
	)
	(footprint ""
		(layer "F.Cu")
		(at 351.249488 -408.517344 -90)
		(property "Reference" "C932"
			(at 0 0 270)
			(layer "F.SilkS")
			(hide yes)
			(effects
				(font
					(size 1.27 1.27)
				)
			)
		)
		(property "Value" ""
			(at 0 0 270)
			(layer "F.Fab")
			(effects
				(font
					(size 1.27 1.27)
				)
			)
		)
		(duplicate_pad_numbers_are_jumpers no)
		(fp_line
			(start -0.299974 0.150114)
			(end -0.299974 -0.150114)
			(stroke
				(width 0.1)
				(type default)
			)
			(layer "F.Fab")
		)
		(fp_line
			(start 0.299974 0.150114)
			(end -0.299974 0.150114)
			(stroke
				(width 0.1)
				(type default)
			)
			(layer "F.Fab")
		)
		(fp_line
			(start -0.299974 -0.150114)
			(end 0.299974 -0.150114)
			(stroke
				(width 0.1)
				(type default)
			)
			(layer "F.Fab")
		)
		(fp_line
			(start 0.299974 -0.150114)
			(end 0.299974 0.150114)
			(stroke
				(width 0.1)
				(type default)
			)
			(layer "F.Fab")
		)
		(pad "1" smd rect
			(at -0.2667 0 270)
			(size 0.3048 0.381)
			(layers "F.Cu" "F.Mask" "F.Paste")
			(net "P5E_CPU0_PE0_TX_C_DN<0>")
		)
		(pad "2" smd rect
			(at 0.2667 0 270)
			(size 0.3048 0.381)
			(layers "F.Cu" "F.Mask" "F.Paste")
			(net "P5E_CPU0_PE0_TX_DN<0>")
		)
	)
)
